(kicad_pcb
	(version 20260206)
	(generator "pcbnew")
	(generator_version "10.0")
	(general
		(thickness 1.6)
		(legacy_teardrops no)
	)
	(paper "A4")
	(title_block
		(title "Wiwynn_Tioga_Pass_MB.brd")
		(comment 1 "Tioga Pass / footprints 3544-3551 of 4770")
	)
	(layers
		(0 "F.Cu" signal "TOP")
		(4 "In1.Cu" signal "L2GND")
		(6 "In2.Cu" signal "L3")
		(8 "In3.Cu" signal "L4GND")
		(10 "In4.Cu" signal "L5")
		(12 "In5.Cu" signal "L6GND")
		(14 "In6.Cu" signal "L7VCC")
		(16 "In7.Cu" signal "L8VCC")
		(18 "In8.Cu" signal "L9GND")
		(20 "In9.Cu" signal "L10")
		(22 "In10.Cu" signal "L11GND")
		(24 "In11.Cu" signal "L12")
		(26 "In12.Cu" signal "L13GND")
		(2 "B.Cu" signal "BOTTOM")
		(9 "F.Adhes" user "F.Adhesive")
		(11 "B.Adhes" user "B.Adhesive")
		(13 "F.Paste" user "Package Geometry/Pastemask Top")
		(15 "B.Paste" user "Package Geometry/Pastemask Bottom")
		(5 "F.SilkS" user "Ref Des/Silkscreen Top")
		(7 "B.SilkS" user "Ref Des/Silkscreen Bottom")
		(1 "F.Mask" user "Board Geometry/Soldermask Top")
		(3 "B.Mask" user "Board Geometry/Soldermask Bottom")
		(17 "Dwgs.User" user "User.Drawings")
		(19 "Cmts.User" user "User.Comments")
		(21 "Eco1.User" user "User.Eco1")
		(23 "Eco2.User" user "User.Eco2")
		(25 "Edge.Cuts" user "Board Geometry/Outline")
		(27 "Margin" user)
		(31 "F.CrtYd" user "Package Geometry/Place Bound Top")
		(29 "B.CrtYd" user "Package Geometry/Place Bound Bottom")
		(35 "F.Fab" user "Ref Des/Assembly Top")
		(33 "B.Fab" user "Ref Des/Assembly Bottom")
	)
	(footprint ""
		(layer "B.Cu")
		(at 447.9036 -18.1102 -90)
		(property "Reference" "R3W9"
			(at 0.8382 -0.67818 270)
			(unlocked yes)
			(layer "B.SilkS")
			(effects
				(font
					(size 0.4064 0.254)
					(thickness 0.1524)
				)
				(justify left mirror)
			)
		)
		(property "Value" ""
			(at 0 0 90)
			(layer "B.Fab")
			(effects
				(font
					(size 1.27 1.27)
				)
				(justify mirror)
			)
		)
		(duplicate_pad_numbers_are_jumpers no)
		(fp_poly
			(pts
				(xy 0.2794 -0.1016) (xy -0.2794 -0.1016) (xy -0.2794 0.9906) (xy 0.2794 0.9906)
			)
			(stroke
				(width 0)
				(type default)
			)
			(fill no)
			(layer "B.CrtYd")
		)
		(fp_line
			(start -0.2794 0.9906)
			(end -0.2794 -0.1016)
			(stroke
				(width 0.1)
				(type default)
			)
			(layer "B.Fab")
		)
		(fp_line
			(start 0.2794 0.9906)
			(end -0.2794 0.9906)
			(stroke
				(width 0.1)
				(type default)
			)
			(layer "B.Fab")
		)
		(fp_line
			(start -0.2794 -0.1016)
			(end 0.2794 -0.1016)
			(stroke
				(width 0.1)
				(type default)
			)
			(layer "B.Fab")
		)
		(fp_line
			(start 0.2794 -0.1016)
			(end 0.2794 0.9906)
			(stroke
				(width 0.1)
				(type default)
			)
			(layer "B.Fab")
		)
		(pad "1" smd rect
			(at 0 0 90)
			(size 0.508 0.508)
			(layers "B.Cu" "B.Mask" "B.Paste")
			(net "VREF_2V2")
		)
		(pad "2" smd rect
			(at 0 0.889 90)
			(size 0.508 0.508)
			(layers "B.Cu" "B.Mask" "B.Paste")
			(net "GND")
		)
		(zone
			(layer "B.Cu")
			(hatch none 0.5)
			(connect_pads
				(clearance 0)
			)
			(min_thickness 0.25)
			(keepout
				(tracks not_allowed)
				(vias allowed)
				(pads allowed)
				(copperpour not_allowed)
				(footprints allowed)
			)
			(placement
				(enabled no)
				(sheetname "")
			)
			(fill
				(thermal_gap 0.5)
				(thermal_bridge_width 0.5)
				(island_removal_mode 0)
			)
			(polygon
				(pts
					(xy 447.2686 -17.8562) (xy 447.2686 -18.3642) (xy 447.6496 -18.3642) (xy 447.6496 -17.8562)
				)
			)
		)
		(zone
			(layer "B.Cu")
			(hatch none 0.5)
			(connect_pads
				(clearance 0)
			)
			(min_thickness 0.25)
			(keepout
				(tracks allowed)
				(vias not_allowed)
				(pads allowed)
				(copperpour not_allowed)
				(footprints allowed)
			)
			(placement
				(enabled no)
				(sheetname "")
			)
			(fill
				(thermal_gap 0.5)
				(thermal_bridge_width 0.5)
				(island_removal_mode 0)
			)
			(polygon
				(pts
					(xy 447.6496 -17.8562) (xy 447.6496 -18.3642) (xy 447.2686 -18.3642) (xy 447.2686 -17.8562)
				)
			)
		)
	)
	(footprint ""
		(layer "B.Cu")
		(at 266.397232 -140.208 90)
		(property "Reference" "C5G73"
			(at -1.14681 0.76708 180)
			(unlocked yes)
			(layer "B.SilkS")
			(effects
				(font
					(size 0.7874 0.5842)
					(thickness 0.1524)
				)
				(justify mirror)
			)
		)
		(property "Value" ""
			(at 0 0 90)
			(layer "B.Fab")
			(effects
				(font
					(size 1.27 1.27)
				)
				(justify mirror)
			)
		)
		(duplicate_pad_numbers_are_jumpers no)
		(fp_rect
			(start -0.4953 -0.2032)
			(end 0.4953 1.6002)
			(stroke
				(width 0)
				(type default)
			)
			(fill no)
			(layer "B.CrtYd")
		)
		(fp_line
			(start 0.4953 -0.2032)
			(end -0.4953 -0.2032)
			(stroke
				(width 0.1)
				(type default)
			)
			(layer "B.Fab")
		)
		(fp_line
			(start -0.4953 -0.2032)
			(end -0.4953 1.6002)
			(stroke
				(width 0.1)
				(type default)
			)
			(layer "B.Fab")
		)
		(fp_line
			(start 0.4953 1.6002)
			(end 0.4953 -0.2032)
			(stroke
				(width 0.1)
				(type default)
			)
			(layer "B.Fab")
		)
		(fp_line
			(start -0.4953 1.6002)
			(end 0.4953 1.6002)
			(stroke
				(width 0.1)
				(type default)
			)
			(layer "B.Fab")
		)
		(pad "1" smd rect
			(at 0 0 270)
			(size 0.762 0.889)
			(layers "B.Cu" "B.Mask" "B.Paste")
			(net "PVDDQ_DEF")
		)
		(pad "2" smd rect
			(at 0 1.397 270)
			(size 0.762 0.889)
			(layers "B.Cu" "B.Mask" "B.Paste")
			(net "GND")
		)
		(zone
			(layer "B.Cu")
			(hatch none 0.5)
			(connect_pads
				(clearance 0)
			)
			(min_thickness 0.25)
			(keepout
				(tracks not_allowed)
				(vias allowed)
				(pads allowed)
				(copperpour not_allowed)
				(footprints allowed)
			)
			(placement
				(enabled no)
				(sheetname "")
			)
			(fill
				(thermal_gap 0.5)
				(thermal_bridge_width 0.5)
				(island_removal_mode 0)
			)
			(polygon
				(pts
					(xy 266.841732 -139.827) (xy 267.349732 -139.827) (xy 267.349732 -140.589) (xy 266.841732 -140.589)
				)
			)
		)
	)
	(footprint ""
		(layer "B.Cu")
		(at 396.018766 -157.117288 -90)
		(property "Reference" "CF24"
			(at 0 0 90)
			(layer "B.SilkS")
			(hide yes)
			(effects
				(font
					(size 1.27 1.27)
				)
				(justify mirror)
			)
		)
		(property "Value" "*"
			(at -1.1811 -2.8194 270)
			(unlocked yes)
			(layer "B.Fab")
			(hide yes)
			(effects
				(font
					(size 1.27 1.016)
					(thickness 0.1524)
				)
				(justify mirror)
			)
		)
		(property "Device Type" "SC22P50V2JN-4GP_SMD-BCG-SC22P5A"
			(at -1.1811 -4.3434 270)
			(unlocked yes)
			(layer "B.Fab")
			(hide yes)
			(effects
				(font
					(size 1.27 1.016)
					(thickness 0.1524)
				)
				(justify mirror)
			)
		)
		(duplicate_pad_numbers_are_jumpers no)
		(fp_rect
			(start 0.4318 0.9525)
			(end -0.4318 -0.9525)
			(stroke
				(width 0)
				(type default)
			)
			(fill no)
			(layer "B.CrtYd")
		)
		(fp_rect
			(start 0.4318 0.9525)
			(end -0.4318 -0.9525)
			(stroke
				(width 0)
				(type default)
			)
			(fill no)
			(layer "B.Fab")
		)
		(pad "1" smd custom
			(at 0 -0.4445 90)
			(size 0.1524 0.1524)
			(layers "B.Cu" "B.Mask" "B.Paste")
			(net "VR_P1V05_PCH_BIREF1")
			(options
				(clearance outline)
				(anchor circle)
			)
			(primitives
				(gr_poly
					(pts
						(arc
							(start 0.3048 0.2032)
							(mid 0.275042 0.275042)
							(end 0.2032 0.3048)
						)
						(arc
							(start -0.2032 0.3048)
							(mid -0.275042 0.275042)
							(end -0.3048 0.2032)
						)
						(arc
							(start -0.3048 -0.2032)
							(mid -0.275042 -0.275042)
							(end -0.2032 -0.3048)
						)
						(arc
							(start 0.2032 -0.3048)
							(mid 0.275042 -0.275042)
							(end 0.3048 -0.2032)
						)
					)
					(width 0)
					(fill yes)
				)
			)
		)
		(pad "2" smd custom
			(at 0 0.4445 90)
			(size 0.1524 0.1524)
			(layers "B.Cu" "B.Mask" "B.Paste")
			(net "ISENSE_P1V05_PCH_STBY_PH1_IMON")
			(options
				(clearance outline)
				(anchor circle)
			)
			(primitives
				(gr_poly
					(pts
						(arc
							(start 0.3048 0.2032)
							(mid 0.275042 0.275042)
							(end 0.2032 0.3048)
						)
						(arc
							(start -0.2032 0.3048)
							(mid -0.275042 0.275042)
							(end -0.3048 0.2032)
						)
						(arc
							(start -0.3048 -0.2032)
							(mid -0.275042 -0.275042)
							(end -0.2032 -0.3048)
						)
						(arc
							(start 0.2032 -0.3048)
							(mid 0.275042 -0.275042)
							(end 0.3048 -0.2032)
						)
					)
					(width 0)
					(fill yes)
				)
			)
		)
	)
	(footprint ""
		(layer "B.Cu")
		(at 379.3998 -154.467306)
		(property "Reference" "C3L8"
			(at 0 0 0)
			(layer "B.SilkS")
			(hide yes)
			(effects
				(font
					(size 1.27 1.27)
				)
				(justify mirror)
			)
		)
		(property "Value" ""
			(at 0 0 0)
			(layer "B.Fab")
			(effects
				(font
					(size 1.27 1.27)
				)
				(justify mirror)
			)
		)
		(duplicate_pad_numbers_are_jumpers no)
		(fp_poly
			(pts
				(xy 0.7239 -0.2159) (xy -0.7239 -0.2159) (xy -0.7239 1.9939) (xy 0.7239 1.9939)
			)
			(stroke
				(width 0)
				(type default)
			)
			(fill no)
			(layer "B.CrtYd")
		)
		(fp_line
			(start -0.7239 -0.2159)
			(end 0.7239 -0.2159)
			(stroke
				(width 0.1)
				(type default)
			)
			(layer "B.Fab")
		)
		(fp_line
			(start -0.7239 1.9939)
			(end -0.7239 -0.2159)
			(stroke
				(width 0.1)
				(type default)
			)
			(layer "B.Fab")
		)
		(fp_line
			(start 0.7239 -0.2159)
			(end 0.7239 1.9939)
			(stroke
				(width 0.1)
				(type default)
			)
			(layer "B.Fab")
		)
		(fp_line
			(start 0.7239 1.9939)
			(end -0.7239 1.9939)
			(stroke
				(width 0.1)
				(type default)
			)
			(layer "B.Fab")
		)
		(pad "1" smd rect
			(at 0 0 180)
			(size 1.27 1.016)
			(layers "B.Cu" "B.Mask" "B.Paste")
			(net "VR_FET_SW_P12V_STBY_PVDDQ_DEF")
		)
		(pad "2" smd rect
			(at 0 1.778 180)
			(size 1.27 1.016)
			(layers "B.Cu" "B.Mask" "B.Paste")
			(net "GND")
		)
		(zone
			(layer "B.Cu")
			(hatch none 0.5)
			(connect_pads
				(clearance 0)
			)
			(min_thickness 0.25)
			(keepout
				(tracks not_allowed)
				(vias allowed)
				(pads allowed)
				(copperpour not_allowed)
				(footprints allowed)
			)
			(placement
				(enabled no)
				(sheetname "")
			)
			(fill
				(thermal_gap 0.5)
				(thermal_bridge_width 0.5)
				(island_removal_mode 0)
			)
			(polygon
				(pts
					(xy 380.0348 -153.959306) (xy 378.7648 -153.959306) (xy 378.7648 -153.197306) (xy 380.0348 -153.197306)
				)
			)
		)
	)
	(footprint ""
		(layer "B.Cu")
		(at 412.313374 -48.687482 -90)
		(property "Reference" "R8F37"
			(at 0 0 90)
			(layer "B.SilkS")
			(hide yes)
			(effects
				(font
					(size 1.27 1.27)
				)
				(justify mirror)
			)
		)
		(property "Value" ""
			(at 0 0 90)
			(layer "B.Fab")
			(effects
				(font
					(size 1.27 1.27)
				)
				(justify mirror)
			)
		)
		(duplicate_pad_numbers_are_jumpers no)
		(fp_poly
			(pts
				(xy 0.2794 -0.1016) (xy -0.2794 -0.1016) (xy -0.2794 0.9906) (xy 0.2794 0.9906)
			)
			(stroke
				(width 0)
				(type default)
			)
			(fill no)
			(layer "B.CrtYd")
		)
		(fp_line
			(start -0.2794 0.9906)
			(end -0.2794 -0.1016)
			(stroke
				(width 0.1)
				(type default)
			)
			(layer "B.Fab")
		)
		(fp_line
			(start 0.2794 0.9906)
			(end -0.2794 0.9906)
			(stroke
				(width 0.1)
				(type default)
			)
			(layer "B.Fab")
		)
		(fp_line
			(start -0.2794 -0.1016)
			(end 0.2794 -0.1016)
			(stroke
				(width 0.1)
				(type default)
			)
			(layer "B.Fab")
		)
		(fp_line
			(start 0.2794 -0.1016)
			(end 0.2794 0.9906)
			(stroke
				(width 0.1)
				(type default)
			)
			(layer "B.Fab")
		)
		(pad "1" smd rect
			(at 0 0 90)
			(size 0.508 0.508)
			(layers "B.Cu" "B.Mask" "B.Paste")
			(net "FM_CPU_ERR0_LVT3_N")
		)
		(pad "2" smd rect
			(at 0 0.889 90)
			(size 0.508 0.508)
			(layers "B.Cu" "B.Mask" "B.Paste")
			(net "FM_CPU_ERR0_PCH_N")
		)
		(zone
			(layer "B.Cu")
			(hatch none 0.5)
			(connect_pads
				(clearance 0)
			)
			(min_thickness 0.25)
			(keepout
				(tracks not_allowed)
				(vias allowed)
				(pads allowed)
				(copperpour not_allowed)
				(footprints allowed)
			)
			(placement
				(enabled no)
				(sheetname "")
			)
			(fill
				(thermal_gap 0.5)
				(thermal_bridge_width 0.5)
				(island_removal_mode 0)
			)
			(polygon
				(pts
					(xy 411.678374 -48.433482) (xy 411.678374 -48.941482) (xy 412.059374 -48.941482) (xy 412.059374 -48.433482)
				)
			)
		)
		(zone
			(layer "B.Cu")
			(hatch none 0.5)
			(connect_pads
				(clearance 0)
			)
			(min_thickness 0.25)
			(keepout
				(tracks allowed)
				(vias not_allowed)
				(pads allowed)
				(copperpour not_allowed)
				(footprints allowed)
			)
			(placement
				(enabled no)
				(sheetname "")
			)
			(fill
				(thermal_gap 0.5)
				(thermal_bridge_width 0.5)
				(island_removal_mode 0)
			)
			(polygon
				(pts
					(xy 412.059374 -48.433482) (xy 412.059374 -48.941482) (xy 411.678374 -48.941482) (xy 411.678374 -48.433482)
				)
			)
		)
	)
	(footprint ""
		(layer "B.Cu")
		(at 448.55638 -32.4485 90)
		(property "Reference" "R25W27"
			(at 0 0 90)
			(layer "B.SilkS")
			(hide yes)
			(effects
				(font
					(size 1.27 1.27)
				)
				(justify mirror)
			)
		)
		(property "Value" "*"
			(at -0.064008 -4.108196 90)
			(unlocked yes)
			(layer "B.Fab")
			(hide yes)
			(effects
				(font
					(size 1.27 1.016)
					(thickness 0.1524)
				)
				(justify mirror)
			)
		)
		(property "Device Type" "120R2F-GP_RCL_GP-120R2F-GP,64.A"
			(at -0.064008 -5.632196 90)
			(unlocked yes)
			(layer "B.Fab")
			(hide yes)
			(effects
				(font
					(size 1.27 1.016)
					(thickness 0.1524)
				)
				(justify mirror)
			)
		)
		(duplicate_pad_numbers_are_jumpers no)
		(fp_line
			(start 0.508 -0.9398)
			(end 0.508 0.9398)
			(stroke
				(width 0.1524)
				(type default)
			)
			(layer "B.SilkS")
		)
		(fp_line
			(start -0.508 -0.9398)
			(end 0.508 -0.9398)
			(stroke
				(width 0.1524)
				(type default)
			)
			(layer "B.SilkS")
		)
		(fp_rect
			(start 0.508 0.9398)
			(end -0.508 -0.9398)
			(stroke
				(width 0)
				(type default)
			)
			(fill no)
			(layer "B.CrtYd")
		)
		(fp_rect
			(start 0.508 0.9398)
			(end -0.508 -0.9398)
			(stroke
				(width 0)
				(type default)
			)
			(fill no)
			(layer "B.Fab")
		)
		(pad "1" smd custom
			(at 0 -0.4445 270)
			(size 0.1397 0.1397)
			(layers "B.Cu" "B.Mask" "B.Paste")
			(net "BMC_M_CKE")
			(options
				(clearance outline)
				(anchor circle)
			)
			(primitives
				(gr_poly
					(pts
						(arc
							(start -0.1778 0.2794)
							(mid -0.249642 0.249642)
							(end -0.2794 0.1778)
						)
						(arc
							(start -0.2794 -0.1778)
							(mid -0.249642 -0.249642)
							(end -0.1778 -0.2794)
						)
						(arc
							(start 0.1778 -0.2794)
							(mid 0.249642 -0.249642)
							(end 0.2794 -0.1778)
						)
						(arc
							(start 0.2794 0.1778)
							(mid 0.249642 0.249642)
							(end 0.1778 0.2794)
						)
					)
					(width 0)
					(fill yes)
				)
			)
		)
		(pad "2" smd custom
			(at 0 0.4445 270)
			(size 0.1397 0.1397)
			(layers "B.Cu" "B.Mask" "B.Paste")
			(net "P1V2_AUX_BMC")
			(options
				(clearance outline)
				(anchor circle)
			)
			(primitives
				(gr_poly
					(pts
						(arc
							(start -0.1778 0.2794)
							(mid -0.249642 0.249642)
							(end -0.2794 0.1778)
						)
						(arc
							(start -0.2794 -0.1778)
							(mid -0.249642 -0.249642)
							(end -0.1778 -0.2794)
						)
						(arc
							(start 0.1778 -0.2794)
							(mid 0.249642 -0.249642)
							(end 0.2794 -0.1778)
						)
						(arc
							(start 0.2794 0.1778)
							(mid 0.249642 0.249642)
							(end 0.1778 0.2794)
						)
					)
					(width 0)
					(fill yes)
				)
			)
		)
	)
	(footprint ""
		(layer "B.Cu")
		(at 272.861532 -140.208 90)
		(property "Reference" "C5G75"
			(at -1.14681 0.76708 180)
			(unlocked yes)
			(layer "B.SilkS")
			(effects
				(font
					(size 0.7874 0.5842)
					(thickness 0.1524)
				)
				(justify mirror)
			)
		)
		(property "Value" ""
			(at 0 0 90)
			(layer "B.Fab")
			(effects
				(font
					(size 1.27 1.27)
				)
				(justify mirror)
			)
		)
		(duplicate_pad_numbers_are_jumpers no)
		(fp_rect
			(start -0.4953 -0.2032)
			(end 0.4953 1.6002)
			(stroke
				(width 0)
				(type default)
			)
			(fill no)
			(layer "B.CrtYd")
		)
		(fp_line
			(start 0.4953 -0.2032)
			(end -0.4953 -0.2032)
			(stroke
				(width 0.1)
				(type default)
			)
			(layer "B.Fab")
		)
		(fp_line
			(start -0.4953 -0.2032)
			(end -0.4953 1.6002)
			(stroke
				(width 0.1)
				(type default)
			)
			(layer "B.Fab")
		)
		(fp_line
			(start 0.4953 1.6002)
			(end 0.4953 -0.2032)
			(stroke
				(width 0.1)
				(type default)
			)
			(layer "B.Fab")
		)
		(fp_line
			(start -0.4953 1.6002)
			(end 0.4953 1.6002)
			(stroke
				(width 0.1)
				(type default)
			)
			(layer "B.Fab")
		)
		(pad "1" smd rect
			(at 0 0 270)
			(size 0.762 0.889)
			(layers "B.Cu" "B.Mask" "B.Paste")
			(net "PVDDQ_DEF")
		)
		(pad "2" smd rect
			(at 0 1.397 270)
			(size 0.762 0.889)
			(layers "B.Cu" "B.Mask" "B.Paste")
			(net "GND")
		)
		(zone
			(layer "B.Cu")
			(hatch none 0.5)
			(connect_pads
				(clearance 0)
			)
			(min_thickness 0.25)
			(keepout
				(tracks not_allowed)
				(vias allowed)
				(pads allowed)
				(copperpour not_allowed)
				(footprints allowed)
			)
			(placement
				(enabled no)
				(sheetname "")
			)
			(fill
				(thermal_gap 0.5)
				(thermal_bridge_width 0.5)
				(island_removal_mode 0)
			)
			(polygon
				(pts
					(xy 273.306032 -139.827) (xy 273.814032 -139.827) (xy 273.814032 -140.589) (xy 273.306032 -140.589)
				)
			)
		)
	)
	(footprint ""
		(layer "B.Cu")
		(at 164.973 -67.2592 90)
		(property "Reference" "R6P40"
			(at 0 0 90)
			(layer "B.SilkS")
			(hide yes)
			(effects
				(font
					(size 1.27 1.27)
				)
				(justify mirror)
			)
		)
		(property "Value" ""
			(at 0 0 90)
			(layer "B.Fab")
			(effects
				(font
					(size 1.27 1.27)
				)
				(justify mirror)
			)
		)
		(duplicate_pad_numbers_are_jumpers no)
		(fp_poly
			(pts
				(xy 0.2794 -0.1016) (xy -0.2794 -0.1016) (xy -0.2794 0.9906) (xy 0.2794 0.9906)
			)
			(stroke
				(width 0)
				(type default)
			)
			(fill no)
			(layer "B.CrtYd")
		)
		(fp_line
			(start 0.2794 -0.1016)
			(end 0.2794 0.9906)
			(stroke
				(width 0.1)
				(type default)
			)
			(layer "B.Fab")
		)
		(fp_line
			(start -0.2794 -0.1016)
			(end 0.2794 -0.1016)
			(stroke
				(width 0.1)
				(type default)
			)
			(layer "B.Fab")
		)
		(fp_line
			(start 0.2794 0.9906)
			(end -0.2794 0.9906)
			(stroke
				(width 0.1)
				(type default)
			)
			(layer "B.Fab")
		)
		(fp_line
			(start -0.2794 0.9906)
			(end -0.2794 -0.1016)
			(stroke
				(width 0.1)
				(type default)
			)
			(layer "B.Fab")
		)
		(pad "1" smd rect
			(at 0 0 270)
			(size 0.508 0.508)
			(layers "B.Cu" "B.Mask" "B.Paste")
			(net "P3V3_STBY")
		)
		(pad "2" smd rect
			(at 0 0.889 270)
			(size 0.508 0.508)
			(layers "B.Cu" "B.Mask" "B.Paste")
			(net "VR_PVCCIO_CPU1_EN")
		)
		(zone
			(layer "B.Cu")
			(hatch none 0.5)
			(connect_pads
				(clearance 0)
			)
			(min_thickness 0.25)
			(keepout
				(tracks allowed)
				(vias not_allowed)
				(pads allowed)
				(copperpour not_allowed)
				(footprints allowed)
			)
			(placement
				(enabled no)
				(sheetname "")
			)
			(fill
				(thermal_gap 0.5)
				(thermal_bridge_width 0.5)
				(island_removal_mode 0)
			)
			(polygon
				(pts
					(xy 165.227 -67.5132) (xy 165.227 -67.0052) (xy 165.608 -67.0052) (xy 165.608 -67.5132)
				)
			)
		)
		(zone
			(layer "B.Cu")
			(hatch none 0.5)
			(connect_pads
				(clearance 0)
			)
			(min_thickness 0.25)
			(keepout
				(tracks not_allowed)
				(vias allowed)
				(pads allowed)
				(copperpour not_allowed)
				(footprints allowed)
			)
			(placement
				(enabled no)
				(sheetname "")
			)
			(fill
				(thermal_gap 0.5)
				(thermal_bridge_width 0.5)
				(island_removal_mode 0)
			)
			(polygon
				(pts
					(xy 165.608 -67.5132) (xy 165.608 -67.0052) (xy 165.227 -67.0052) (xy 165.227 -67.5132)
				)
			)
		)
	)
)
